# BASEBOARD_FAB2 (Tioga Pass) — schematic netlist excerpt (pin names and nets, part order shuffled) for the footprints in the layout excerpt that follows; sources: Cadence DE-HDL packaged netlist, KiCad conversion of Wiwynn_Tioga_Pass_MB.brd

C4G3  CAP_A  0.01UF 25V 10% X7R  pkg 0402V  page 45 : A = M_B_VREF ; B = GND
R1T27  RES  240 1.0% CHIP  pkg 0402  page 143 : A = GND ; B = BMC_MIOZ
R9F67  RES  0.0 5% CHIP  pkg 0402  page 181 : A = SP2_BMC_CM_UART_RX_R1 ; B = SPA_MID_DBG_TX_R

(kicad_pcb
	(version 20260206)
	(generator "pcbnew")
	(generator_version "10.0")
	(general
		(thickness 1.6)
		(legacy_teardrops no)
	)
	(paper "A4")
	(title_block
		(title "Wiwynn_Tioga_Pass_MB.brd")
		(comment 1 "Tioga Pass / footprints 2078-2080 of 4770")
	)
	(layers
		(0 "F.Cu" signal "TOP")
		(4 "In1.Cu" signal "L2GND")
		(6 "In2.Cu" signal "L3")
		(8 "In3.Cu" signal "L4GND")
		(10 "In4.Cu" signal "L5")
		(12 "In5.Cu" signal "L6GND")
		(14 "In6.Cu" signal "L7VCC")
		(16 "In7.Cu" signal "L8VCC")
		(18 "In8.Cu" signal "L9GND")
		(20 "In9.Cu" signal "L10")
		(22 "In10.Cu" signal "L11GND")
		(24 "In11.Cu" signal "L12")
		(26 "In12.Cu" signal "L13GND")
		(2 "B.Cu" signal "BOTTOM")
		(9 "F.Adhes" user "F.Adhesive")
		(11 "B.Adhes" user "B.Adhesive")
		(13 "F.Paste" user "Package Geometry/Pastemask Top")
		(15 "B.Paste" user "Package Geometry/Pastemask Bottom")
		(5 "F.SilkS" user "Ref Des/Silkscreen Top")
		(7 "B.SilkS" user "Ref Des/Silkscreen Bottom")
		(1 "F.Mask" user "Board Geometry/Soldermask Top")
		(3 "B.Mask" user "Board Geometry/Soldermask Bottom")
		(17 "Dwgs.User" user "User.Drawings")
		(19 "Cmts.User" user "User.Comments")
		(21 "Eco1.User" user "User.Eco1")
		(23 "Eco2.User" user "User.Eco2")
		(25 "Edge.Cuts" user "Board Geometry/Outline")
		(27 "Margin" user)
		(31 "F.CrtYd" user "Package Geometry/Place Bound Top")
		(29 "B.CrtYd" user "Package Geometry/Place Bound Bottom")
		(35 "F.Fab" user "Ref Des/Assembly Top")
		(33 "B.Fab" user "Ref Des/Assembly Bottom")
	)
	(footprint ""
		(layer "F.Cu")
		(at 195.58 -12.923012 90)
		(property "Reference" "C4G3"
			(at 0 0 90)
			(layer "F.SilkS")
			(hide yes)
			(effects
				(font
					(size 1.27 1.27)
				)
			)
		)
		(property "Value" ""
			(at 0 0 90)
			(layer "F.Fab")
			(effects
				(font
					(size 1.27 1.27)
				)
			)
		)
		(duplicate_pad_numbers_are_jumpers no)
		(fp_poly
			(pts
				(xy 0.3048 -0.1016) (xy 0.3048 0.9906) (xy -0.3048 0.9906) (xy -0.3048 -0.1016)
			)
			(stroke
				(width 0)
				(type default)
			)
			(fill no)
			(layer "F.CrtYd")
		)
		(fp_line
			(start 0.3048 -0.1016)
			(end -0.3048 -0.1016)
			(stroke
				(width 0.1)
				(type default)
			)
			(layer "F.Fab")
		)
		(fp_line
			(start -0.3048 -0.1016)
			(end -0.3048 0.9906)
			(stroke
				(width 0.1)
				(type default)
			)
			(layer "F.Fab")
		)
		(fp_line
			(start 0.3048 0.9906)
			(end 0.3048 -0.1016)
			(stroke
				(width 0.1)
				(type default)
			)
			(layer "F.Fab")
		)
		(fp_line
			(start -0.3048 0.9906)
			(end 0.3048 0.9906)
			(stroke
				(width 0.1)
				(type default)
			)
			(layer "F.Fab")
		)
		(pad "1" smd rect
			(at 0 0 90)
			(size 0.508 0.508)
			(layers "F.Cu" "F.Mask" "F.Paste")
			(net "M_B_VREF")
		)
		(pad "2" smd rect
			(at 0 0.889 90)
			(size 0.508 0.508)
			(layers "F.Cu" "F.Mask" "F.Paste")
			(net "GND")
		)
		(zone
			(layer "F.Cu")
			(hatch none 0.5)
			(connect_pads
				(clearance 0)
			)
			(min_thickness 0.25)
			(keepout
				(tracks allowed)
				(vias not_allowed)
				(pads allowed)
				(copperpour not_allowed)
				(footprints allowed)
			)
			(placement
				(enabled no)
				(sheetname "")
			)
			(fill
				(thermal_gap 0.5)
				(thermal_bridge_width 0.5)
				(island_removal_mode 0)
			)
			(polygon
				(pts
					(xy 195.834 -12.669012) (xy 195.834 -13.177012) (xy 196.215 -13.177012) (xy 196.215 -12.669012)
				)
			)
		)
		(zone
			(layer "F.Cu")
			(hatch none 0.5)
			(connect_pads
				(clearance 0)
			)
			(min_thickness 0.25)
			(keepout
				(tracks not_allowed)
				(vias allowed)
				(pads allowed)
				(copperpour not_allowed)
				(footprints allowed)
			)
			(placement
				(enabled no)
				(sheetname "")
			)
			(fill
				(thermal_gap 0.5)
				(thermal_bridge_width 0.5)
				(island_removal_mode 0)
			)
			(polygon
				(pts
					(xy 196.215 -12.669012) (xy 196.215 -13.177012) (xy 195.834 -13.177012) (xy 195.834 -12.669012)
				)
			)
		)
	)
	(footprint ""
		(layer "F.Cu")
		(at 485.875076 -28.104084)
		(property "Reference" "R9F67"
			(at 0 0 0)
			(layer "F.SilkS")
			(hide yes)
			(effects
				(font
					(size 1.27 1.27)
				)
			)
		)
		(property "Value" ""
			(at 0 0 0)
			(layer "F.Fab")
			(effects
				(font
					(size 1.27 1.27)
				)
			)
		)
		(duplicate_pad_numbers_are_jumpers no)
		(fp_poly
			(pts
				(xy -0.2794 -0.1016) (xy 0.2794 -0.1016) (xy 0.2794 0.9906) (xy -0.2794 0.9906)
			)
			(stroke
				(width 0)
				(type default)
			)
			(fill no)
			(layer "F.CrtYd")
		)
		(fp_line
			(start -0.2794 -0.1016)
			(end -0.2794 0.9906)
			(stroke
				(width 0.1)
				(type default)
			)
			(layer "F.Fab")
		)
		(fp_line
			(start -0.2794 0.9906)
			(end 0.2794 0.9906)
			(stroke
				(width 0.1)
				(type default)
			)
			(layer "F.Fab")
		)
		(fp_line
			(start 0.2794 -0.1016)
			(end -0.2794 -0.1016)
			(stroke
				(width 0.1)
				(type default)
			)
			(layer "F.Fab")
		)
		(fp_line
			(start 0.2794 0.9906)
			(end 0.2794 -0.1016)
			(stroke
				(width 0.1)
				(type default)
			)
			(layer "F.Fab")
		)
		(pad "1" smd rect
			(at 0 0)
			(size 0.508 0.508)
			(layers "F.Cu" "F.Mask" "F.Paste")
			(net "SP2_BMC_CM_UART_RX_R1")
		)
		(pad "2" smd rect
			(at 0 0.889)
			(size 0.508 0.508)
			(layers "F.Cu" "F.Mask" "F.Paste")
			(net "SPA_MID_DBG_TX_R")
		)
		(zone
			(layer "F.Cu")
			(hatch none 0.5)
			(connect_pads
				(clearance 0)
			)
			(min_thickness 0.25)
			(keepout
				(tracks allowed)
				(vias not_allowed)
				(pads allowed)
				(copperpour not_allowed)
				(footprints allowed)
			)
			(placement
				(enabled no)
				(sheetname "")
			)
			(fill
				(thermal_gap 0.5)
				(thermal_bridge_width 0.5)
				(island_removal_mode 0)
			)
			(polygon
				(pts
					(xy 485.621076 -27.850084) (xy 486.129076 -27.850084) (xy 486.129076 -27.469084) (xy 485.621076 -27.469084)
				)
			)
		)
		(zone
			(layer "F.Cu")
			(hatch none 0.5)
			(connect_pads
				(clearance 0)
			)
			(min_thickness 0.25)
			(keepout
				(tracks not_allowed)
				(vias allowed)
				(pads allowed)
				(copperpour not_allowed)
				(footprints allowed)
			)
			(placement
				(enabled no)
				(sheetname "")
			)
			(fill
				(thermal_gap 0.5)
				(thermal_bridge_width 0.5)
				(island_removal_mode 0)
			)
			(polygon
				(pts
					(xy 485.621076 -27.469084) (xy 486.129076 -27.469084) (xy 486.129076 -27.850084) (xy 485.621076 -27.850084)
				)
			)
		)
	)
	(footprint ""
		(layer "F.Cu")
		(at 428.63008 -36.07435 -90)
		(property "Reference" "R1T27"
			(at 0 0 270)
			(layer "F.SilkS")
			(hide yes)
			(effects
				(font
					(size 1.27 1.27)
				)
			)
		)
		(property "Value" ""
			(at 0 0 270)
			(layer "F.Fab")
			(effects
				(font
					(size 1.27 1.27)
				)
			)
		)
		(duplicate_pad_numbers_are_jumpers no)
		(fp_poly
			(pts
				(xy -0.2794 -0.1016) (xy 0.2794 -0.1016) (xy 0.2794 0.9906) (xy -0.2794 0.9906)
			)
			(stroke
				(width 0)
				(type default)
			)
			(fill no)
			(layer "F.CrtYd")
		)
		(fp_line
			(start -0.2794 0.9906)
			(end 0.2794 0.9906)
			(stroke
				(width 0.1)
				(type default)
			)
			(layer "F.Fab")
		)
		(fp_line
			(start 0.2794 0.9906)
			(end 0.2794 -0.1016)
			(stroke
				(width 0.1)
				(type default)
			)
			(layer "F.Fab")
		)
		(fp_line
			(start -0.2794 -0.1016)
			(end -0.2794 0.9906)
			(stroke
				(width 0.1)
				(type default)
			)
			(layer "F.Fab")
		)
		(fp_line
			(start 0.2794 -0.1016)
			(end -0.2794 -0.1016)
			(stroke
				(width 0.1)
				(type default)
			)
			(layer "F.Fab")
		)
		(pad "1" smd rect
			(at 0 0 270)
			(size 0.508 0.508)
			(layers "F.Cu" "F.Mask" "F.Paste")
			(net "GND")
		)
		(pad "2" smd rect
			(at 0 0.889 270)
			(size 0.508 0.508)
			(layers "F.Cu" "F.Mask" "F.Paste")
			(net "BMC_MIOZ")
		)
		(zone
			(layer "F.Cu")
			(hatch none 0.5)
			(connect_pads
				(clearance 0)
			)
			(min_thickness 0.25)
			(keepout
				(tracks not_allowed)
				(vias allowed)
				(pads allowed)
				(copperpour not_allowed)
				(footprints allowed)
			)
			(placement
				(enabled no)
				(sheetname "")
			)
			(fill
				(thermal_gap 0.5)
				(thermal_bridge_width 0.5)
				(island_removal_mode 0)
			)
			(polygon
				(pts
					(xy 427.99508 -36.32835) (xy 427.99508 -35.82035) (xy 428.37608 -35.82035) (xy 428.37608 -36.32835)
				)
			)
		)
		(zone
			(layer "F.Cu")
			(hatch none 0.5)
			(connect_pads
				(clearance 0)
			)
			(min_thickness 0.25)
			(keepout
				(tracks allowed)
				(vias not_allowed)
				(pads allowed)
				(copperpour not_allowed)
				(footprints allowed)
			)
			(placement
				(enabled no)
				(sheetname "")
			)
			(fill
				(thermal_gap 0.5)
				(thermal_bridge_width 0.5)
				(island_removal_mode 0)
			)
			(polygon
				(pts
					(xy 428.37608 -36.32835) (xy 428.37608 -35.82035) (xy 427.99508 -35.82035) (xy 427.99508 -36.32835)
				)
			)
		)
	)
)
